(kicad_pcb
	(version 20260206)
	(generator "pcbnew")
	(generator_version "10.0")
	(general
		(thickness 1.6)
		(legacy_teardrops no)
	)
	(paper "A4")
	(title_block
		(title "v1-chassis-manager — T6M_CM_d_v01_1031_1645.brd")
		(comment 1 "Open CloudServer (Microsoft) / footprints 1670-1679 of 2512")
	)
	(layers
		(0 "F.Cu" signal "TOP")
		(4 "In1.Cu" signal "GND1")
		(6 "In2.Cu" signal "IN1")
		(8 "In3.Cu" signal "VCC1")
		(10 "In4.Cu" signal "VCC2")
		(12 "In5.Cu" signal "GND2")
		(14 "In6.Cu" signal "IN2")
		(16 "In7.Cu" signal "IN3")
		(18 "In8.Cu" signal "GND3")
		(2 "B.Cu" signal "BOTTOM")
		(9 "F.Adhes" user "F.Adhesive")
		(11 "B.Adhes" user "B.Adhesive")
		(13 "F.Paste" user "Package Geometry/Pastemask Top")
		(15 "B.Paste" user "Package Geometry/Pastemask Bottom")
		(5 "F.SilkS" user "Ref Des/Silkscreen Top")
		(7 "B.SilkS" user "Ref Des/Silkscreen Bottom")
		(1 "F.Mask" user "Board Geometry/Soldermask Top")
		(3 "B.Mask" user "Board Geometry/Soldermask Bottom")
		(17 "Dwgs.User" user "User.Drawings")
		(19 "Cmts.User" user "User.Comments")
		(21 "Eco1.User" user "User.Eco1")
		(23 "Eco2.User" user "User.Eco2")
		(25 "Edge.Cuts" user "Board Geometry/Outline")
		(27 "Margin" user)
		(31 "F.CrtYd" user "Package Geometry/Place Bound Top")
		(29 "B.CrtYd" user "Package Geometry/Place Bound Bottom")
		(35 "F.Fab" user "Ref Des/Assembly Top")
		(33 "B.Fab" user "Ref Des/Assembly Bottom")
	)
	(footprint ""
		(layer "B.Cu")
		(at 50.253138 -76.023724 90)
		(property "Reference" "R39"
			(at -32.673798 -15.415768 270)
			(unlocked yes)
			(layer "B.SilkS")
			(effects
				(font
					(size 0.7874 0.5842)
					(thickness 0.1524)
				)
				(justify left mirror)
			)
		)
		(property "Value" ""
			(at 0 0 90)
			(layer "B.Fab")
			(effects
				(font
					(size 1.27 1.27)
				)
				(justify mirror)
			)
		)
		(duplicate_pad_numbers_are_jumpers no)
		(fp_line
			(start 0.7874 -0.4064)
			(end -0.7874 -0.4064)
			(stroke
				(width 0.1524)
				(type default)
			)
			(layer "B.SilkS")
		)
		(fp_line
			(start -0.7874 -0.4064)
			(end -0.7874 0.4064)
			(stroke
				(width 0.1524)
				(type default)
			)
			(layer "B.SilkS")
		)
		(fp_line
			(start 0.7874 0.4064)
			(end 0.7874 -0.4064)
			(stroke
				(width 0.1524)
				(type default)
			)
			(layer "B.SilkS")
		)
		(fp_line
			(start -0.7874 0.4064)
			(end 0.7874 0.4064)
			(stroke
				(width 0.1524)
				(type default)
			)
			(layer "B.SilkS")
		)
		(fp_poly
			(pts
				(xy 0.508 0.2794) (xy 0.508 0.2286) (xy 0.635 0.2286) (xy 0.635 -0.254) (xy 0.5334 -0.254) (xy 0.5334 -0.2794)
				(xy -0.5334 -0.2794) (xy -0.5334 -0.254) (xy -0.635 -0.254) (xy -0.635 0.254) (xy -0.5334 0.254)
				(xy -0.5334 0.2794)
			)
			(stroke
				(width 0)
				(type default)
			)
			(fill no)
			(layer "B.CrtYd")
		)
		(pad "1" smd rect
			(at -0.40005 0 270)
			(size 0.4572 0.508)
			(layers "B.Cu" "B.Mask" "B.Paste")
			(net "PD_CPU_NODE1_AM23")
		)
		(pad "2" smd rect
			(at 0.40005 0 270)
			(size 0.4572 0.508)
			(layers "B.Cu" "B.Mask" "B.Paste")
			(net "GND")
		)
	)
	(footprint ""
		(layer "B.Cu")
		(at 97.50044 -167.554656 90)
		(property "Reference" "R766"
			(at -2.750566 -2.59969 270)
			(unlocked yes)
			(layer "B.SilkS")
			(effects
				(font
					(size 0.7874 0.5842)
					(thickness 0.1524)
				)
				(justify left mirror)
			)
		)
		(property "Value" ""
			(at 0 0 90)
			(layer "B.Fab")
			(effects
				(font
					(size 1.27 1.27)
				)
				(justify mirror)
			)
		)
		(duplicate_pad_numbers_are_jumpers no)
		(fp_line
			(start 0.7874 -0.4064)
			(end -0.7874 -0.4064)
			(stroke
				(width 0.1524)
				(type default)
			)
			(layer "B.SilkS")
		)
		(fp_line
			(start -0.7874 -0.4064)
			(end -0.7874 0.4064)
			(stroke
				(width 0.1524)
				(type default)
			)
			(layer "B.SilkS")
		)
		(fp_line
			(start 0.7874 0.4064)
			(end 0.7874 -0.4064)
			(stroke
				(width 0.1524)
				(type default)
			)
			(layer "B.SilkS")
		)
		(fp_line
			(start -0.7874 0.4064)
			(end 0.7874 0.4064)
			(stroke
				(width 0.1524)
				(type default)
			)
			(layer "B.SilkS")
		)
		(fp_poly
			(pts
				(xy 0.508 0.2794) (xy 0.508 0.2286) (xy 0.635 0.2286) (xy 0.635 -0.254) (xy 0.5334 -0.254) (xy 0.5334 -0.2794)
				(xy -0.5334 -0.2794) (xy -0.5334 -0.254) (xy -0.635 -0.254) (xy -0.635 0.254) (xy -0.5334 0.254)
				(xy -0.5334 0.2794)
			)
			(stroke
				(width 0)
				(type default)
			)
			(fill no)
			(layer "B.CrtYd")
		)
		(pad "1" smd rect
			(at -0.40005 0 270)
			(size 0.4572 0.508)
			(layers "B.Cu" "B.Mask" "B.Paste")
			(net "TMP05_FUNC2")
		)
		(pad "2" smd rect
			(at 0.40005 0 270)
			(size 0.4572 0.508)
			(layers "B.Cu" "B.Mask" "B.Paste")
			(net "P3V3_NODE1")
		)
	)
	(footprint ""
		(layer "B.Cu")
		(at 78.83144 -171.489624 180)
		(property "Reference" "R690"
			(at -30.603698 -20.648676 0)
			(unlocked yes)
			(layer "B.SilkS")
			(effects
				(font
					(size 0.7874 0.5842)
					(thickness 0.1524)
				)
				(justify left mirror)
			)
		)
		(property "Value" ""
			(at 0 0 0)
			(layer "B.Fab")
			(effects
				(font
					(size 1.27 1.27)
				)
				(justify mirror)
			)
		)
		(duplicate_pad_numbers_are_jumpers no)
		(fp_line
			(start 0.7874 0.4064)
			(end 0.7874 -0.4064)
			(stroke
				(width 0.1524)
				(type default)
			)
			(layer "B.SilkS")
		)
		(fp_line
			(start 0.7874 -0.4064)
			(end -0.7874 -0.4064)
			(stroke
				(width 0.1524)
				(type default)
			)
			(layer "B.SilkS")
		)
		(fp_line
			(start -0.7874 0.4064)
			(end 0.7874 0.4064)
			(stroke
				(width 0.1524)
				(type default)
			)
			(layer "B.SilkS")
		)
		(fp_line
			(start -0.7874 -0.4064)
			(end -0.7874 0.4064)
			(stroke
				(width 0.1524)
				(type default)
			)
			(layer "B.SilkS")
		)
		(fp_poly
			(pts
				(xy 0.508 0.2794) (xy 0.508 0.2286) (xy 0.635 0.2286) (xy 0.635 -0.254) (xy 0.5334 -0.254) (xy 0.5334 -0.2794)
				(xy -0.5334 -0.2794) (xy -0.5334 -0.254) (xy -0.635 -0.254) (xy -0.635 0.254) (xy -0.5334 0.254)
				(xy -0.5334 0.2794)
			)
			(stroke
				(width 0)
				(type default)
			)
			(fill no)
			(layer "B.CrtYd")
		)
		(pad "1" smd rect
			(at -0.40005 0)
			(size 0.4572 0.508)
			(layers "B.Cu" "B.Mask" "B.Paste")
			(net "T1_NODE2_EN")
		)
		(pad "2" smd rect
			(at 0.40005 0)
			(size 0.4572 0.508)
			(layers "B.Cu" "B.Mask" "B.Paste")
			(net "P5V_NODE1")
		)
	)
	(footprint ""
		(layer "B.Cu")
		(at 135.196834 -36.359084)
		(property "Reference" "R1181"
			(at -5.415788 18.22831 0)
			(unlocked yes)
			(layer "B.SilkS")
			(effects
				(font
					(size 0.7874 0.5842)
					(thickness 0.1524)
				)
				(justify left mirror)
			)
		)
		(property "Value" ""
			(at 0 0 0)
			(layer "B.Fab")
			(effects
				(font
					(size 1.27 1.27)
				)
				(justify mirror)
			)
		)
		(duplicate_pad_numbers_are_jumpers no)
		(fp_line
			(start -0.7874 -0.4064)
			(end -0.7874 0.4064)
			(stroke
				(width 0.1524)
				(type default)
			)
			(layer "B.SilkS")
		)
		(fp_line
			(start -0.7874 0.4064)
			(end 0.7874 0.4064)
			(stroke
				(width 0.1524)
				(type default)
			)
			(layer "B.SilkS")
		)
		(fp_line
			(start 0.7874 -0.4064)
			(end -0.7874 -0.4064)
			(stroke
				(width 0.1524)
				(type default)
			)
			(layer "B.SilkS")
		)
		(fp_line
			(start 0.7874 0.4064)
			(end 0.7874 -0.4064)
			(stroke
				(width 0.1524)
				(type default)
			)
			(layer "B.SilkS")
		)
		(fp_poly
			(pts
				(xy 0.508 0.2794) (xy 0.508 0.2286) (xy 0.635 0.2286) (xy 0.635 -0.254) (xy 0.5334 -0.254) (xy 0.5334 -0.2794)
				(xy -0.5334 -0.2794) (xy -0.5334 -0.254) (xy -0.635 -0.254) (xy -0.635 0.254) (xy -0.5334 0.254)
				(xy -0.5334 0.2794)
			)
			(stroke
				(width 0)
				(type default)
			)
			(fill no)
			(layer "B.CrtYd")
		)
		(pad "1" smd rect
			(at -0.40005 0 180)
			(size 0.4572 0.508)
			(layers "B.Cu" "B.Mask" "B.Paste")
			(net "CPLD123_RSV1")
		)
		(pad "2" smd rect
			(at 0.40005 0 180)
			(size 0.4572 0.508)
			(layers "B.Cu" "B.Mask" "B.Paste")
			(net "SIO_CPLD_RSV1_R")
		)
	)
	(footprint ""
		(layer "B.Cu")
		(at 122.0978 -42.700702)
		(property "Reference" "R184"
			(at -2.808732 0.132842 0)
			(unlocked yes)
			(layer "B.SilkS")
			(effects
				(font
					(size 0.7874 0.5842)
					(thickness 0.1524)
				)
				(justify left mirror)
			)
		)
		(property "Value" ""
			(at 0 0 0)
			(layer "B.Fab")
			(effects
				(font
					(size 1.27 1.27)
				)
				(justify mirror)
			)
		)
		(duplicate_pad_numbers_are_jumpers no)
		(fp_line
			(start -0.7874 -0.4064)
			(end -0.7874 0.4064)
			(stroke
				(width 0.1524)
				(type default)
			)
			(layer "B.SilkS")
		)
		(fp_line
			(start -0.7874 0.4064)
			(end 0.7874 0.4064)
			(stroke
				(width 0.1524)
				(type default)
			)
			(layer "B.SilkS")
		)
		(fp_line
			(start 0.7874 -0.4064)
			(end -0.7874 -0.4064)
			(stroke
				(width 0.1524)
				(type default)
			)
			(layer "B.SilkS")
		)
		(fp_line
			(start 0.7874 0.4064)
			(end 0.7874 -0.4064)
			(stroke
				(width 0.1524)
				(type default)
			)
			(layer "B.SilkS")
		)
		(fp_poly
			(pts
				(xy 0.508 0.2794) (xy 0.508 0.2286) (xy 0.635 0.2286) (xy 0.635 -0.254) (xy 0.5334 -0.254) (xy 0.5334 -0.2794)
				(xy -0.5334 -0.2794) (xy -0.5334 -0.254) (xy -0.635 -0.254) (xy -0.635 0.254) (xy -0.5334 0.254)
				(xy -0.5334 0.2794)
			)
			(stroke
				(width 0)
				(type default)
			)
			(fill no)
			(layer "B.CrtYd")
		)
		(pad "1" smd rect
			(at -0.40005 0 180)
			(size 0.4572 0.508)
			(layers "B.Cu" "B.Mask" "B.Paste")
			(net "LPC_CPU_NODE1_LAD2")
		)
		(pad "2" smd rect
			(at 0.40005 0 180)
			(size 0.4572 0.508)
			(layers "B.Cu" "B.Mask" "B.Paste")
			(net "LPC_CPU_NODE1_LAD2_SIO")
		)
	)
	(footprint ""
		(layer "B.Cu")
		(at 143.960596 -68.73113 -90)
		(property "Reference" "C338"
			(at -1.050036 -0.550926 270)
			(unlocked yes)
			(layer "B.SilkS")
			(effects
				(font
					(size 0.7874 0.5842)
					(thickness 0.1524)
				)
				(justify left mirror)
			)
		)
		(property "Value" ""
			(at 0 0 90)
			(layer "B.Fab")
			(effects
				(font
					(size 1.27 1.27)
				)
				(justify mirror)
			)
		)
		(duplicate_pad_numbers_are_jumpers no)
		(fp_line
			(start -0.7874 0.4064)
			(end 0.7874 0.4064)
			(stroke
				(width 0.1524)
				(type default)
			)
			(layer "B.SilkS")
		)
		(fp_line
			(start 0.7874 0.4064)
			(end 0.7874 -0.4064)
			(stroke
				(width 0.1524)
				(type default)
			)
			(layer "B.SilkS")
		)
		(fp_line
			(start 0 0.381)
			(end 0 -0.381)
			(stroke
				(width 0.1524)
				(type default)
			)
			(layer "B.SilkS")
		)
		(fp_line
			(start -0.7874 -0.4064)
			(end -0.7874 0.4064)
			(stroke
				(width 0.1524)
				(type default)
			)
			(layer "B.SilkS")
		)
		(fp_line
			(start 0.7874 -0.4064)
			(end -0.7874 -0.4064)
			(stroke
				(width 0.1524)
				(type default)
			)
			(layer "B.SilkS")
		)
		(fp_poly
			(pts
				(xy 0.5334 0.254) (xy 0.635 0.254) (xy 0.635 0.2286) (xy 0.635 -0.254) (xy 0.5334 -0.254) (xy 0.5334 -0.2794)
				(xy -0.5334 -0.2794) (xy -0.5334 -0.254) (xy -0.635 -0.254) (xy -0.635 0.254) (xy -0.5334 0.254)
				(xy -0.5334 0.2794) (xy 0.508 0.2794) (xy 0.5334 0.2794)
			)
			(stroke
				(width 0)
				(type default)
			)
			(fill no)
			(layer "B.CrtYd")
		)
		(pad "1" smd rect
			(at -0.40005 0 90)
			(size 0.4572 0.508)
			(layers "B.Cu" "B.Mask" "B.Paste")
			(net "P1V0_SATA")
		)
		(pad "2" smd rect
			(at 0.40005 0 90)
			(size 0.4572 0.508)
			(layers "B.Cu" "B.Mask" "B.Paste")
			(net "GND")
		)
	)
	(footprint ""
		(layer "B.Cu")
		(at 90.81262 -162.846512)
		(property "Reference" "R781"
			(at 24.774144 20.136104 0)
			(unlocked yes)
			(layer "B.SilkS")
			(effects
				(font
					(size 0.7874 0.5842)
					(thickness 0.1524)
				)
				(justify left mirror)
			)
		)
		(property "Value" ""
			(at 0 0 0)
			(layer "B.Fab")
			(effects
				(font
					(size 1.27 1.27)
				)
				(justify mirror)
			)
		)
		(duplicate_pad_numbers_are_jumpers no)
		(fp_line
			(start -0.7874 -0.4064)
			(end -0.7874 0.4064)
			(stroke
				(width 0.1524)
				(type default)
			)
			(layer "B.SilkS")
		)
		(fp_line
			(start -0.7874 0.4064)
			(end 0.7874 0.4064)
			(stroke
				(width 0.1524)
				(type default)
			)
			(layer "B.SilkS")
		)
		(fp_line
			(start 0.7874 -0.4064)
			(end -0.7874 -0.4064)
			(stroke
				(width 0.1524)
				(type default)
			)
			(layer "B.SilkS")
		)
		(fp_line
			(start 0.7874 0.4064)
			(end 0.7874 -0.4064)
			(stroke
				(width 0.1524)
				(type default)
			)
			(layer "B.SilkS")
		)
		(fp_poly
			(pts
				(xy 0.508 0.2794) (xy 0.508 0.2286) (xy 0.635 0.2286) (xy 0.635 -0.254) (xy 0.5334 -0.254) (xy 0.5334 -0.2794)
				(xy -0.5334 -0.2794) (xy -0.5334 -0.254) (xy -0.635 -0.254) (xy -0.635 0.254) (xy -0.5334 0.254)
				(xy -0.5334 0.2794)
			)
			(stroke
				(width 0)
				(type default)
			)
			(fill no)
			(layer "B.CrtYd")
		)
		(pad "1" smd rect
			(at -0.40005 0 180)
			(size 0.4572 0.508)
			(layers "B.Cu" "B.Mask" "B.Paste")
			(net "I2C_SDC_SCL")
		)
		(pad "2" smd rect
			(at 0.40005 0 180)
			(size 0.4572 0.508)
			(layers "B.Cu" "B.Mask" "B.Paste")
			(net "P3V3_NODE1")
		)
	)
	(footprint ""
		(layer "B.Cu")
		(at 136.382252 -119.487442 180)
		(property "Reference" "C8"
			(at 0.968502 -0.16383 0)
			(unlocked yes)
			(layer "B.SilkS")
			(effects
				(font
					(size 0.7874 0.5842)
					(thickness 0.1524)
				)
				(justify left mirror)
			)
		)
		(property "Value" ""
			(at 0 0 0)
			(layer "B.Fab")
			(effects
				(font
					(size 1.27 1.27)
				)
				(justify mirror)
			)
		)
		(duplicate_pad_numbers_are_jumpers no)
		(fp_line
			(start 0.7874 0.4064)
			(end 0.7874 -0.4064)
			(stroke
				(width 0.1524)
				(type default)
			)
			(layer "B.SilkS")
		)
		(fp_line
			(start 0.7874 -0.4064)
			(end -0.7874 -0.4064)
			(stroke
				(width 0.1524)
				(type default)
			)
			(layer "B.SilkS")
		)
		(fp_line
			(start 0 0.381)
			(end 0 -0.381)
			(stroke
				(width 0.1524)
				(type default)
			)
			(layer "B.SilkS")
		)
		(fp_line
			(start -0.7874 0.4064)
			(end 0.7874 0.4064)
			(stroke
				(width 0.1524)
				(type default)
			)
			(layer "B.SilkS")
		)
		(fp_line
			(start -0.7874 -0.4064)
			(end -0.7874 0.4064)
			(stroke
				(width 0.1524)
				(type default)
			)
			(layer "B.SilkS")
		)
		(fp_poly
			(pts
				(xy 0.5334 0.254) (xy 0.635 0.254) (xy 0.635 0.2286) (xy 0.635 -0.254) (xy 0.5334 -0.254) (xy 0.5334 -0.2794)
				(xy -0.5334 -0.2794) (xy -0.5334 -0.254) (xy -0.635 -0.254) (xy -0.635 0.254) (xy -0.5334 0.254)
				(xy -0.5334 0.2794) (xy 0.508 0.2794) (xy 0.5334 0.2794)
			)
			(stroke
				(width 0)
				(type default)
			)
			(fill no)
			(layer "B.CrtYd")
		)
		(pad "1" smd rect
			(at -0.40005 0)
			(size 0.4572 0.508)
			(layers "B.Cu" "B.Mask" "B.Paste")
			(net "P1V5_CLK_NODE1")
		)
		(pad "2" smd rect
			(at 0.40005 0)
			(size 0.4572 0.508)
			(layers "B.Cu" "B.Mask" "B.Paste")
			(net "GND")
		)
	)
	(footprint ""
		(layer "B.Cu")
		(at 91.102434 -188.858398)
		(property "Reference" "R909"
			(at -2.352294 -3.284474 0)
			(unlocked yes)
			(layer "B.SilkS")
			(effects
				(font
					(size 0.7874 0.5842)
					(thickness 0.1524)
				)
				(justify left mirror)
			)
		)
		(property "Value" ""
			(at 0 0 0)
			(layer "B.Fab")
			(effects
				(font
					(size 1.27 1.27)
				)
				(justify mirror)
			)
		)
		(duplicate_pad_numbers_are_jumpers no)
		(fp_line
			(start -0.7874 -0.4064)
			(end -0.7874 0.4064)
			(stroke
				(width 0.1524)
				(type default)
			)
			(layer "B.SilkS")
		)
		(fp_line
			(start -0.7874 0.4064)
			(end 0.7874 0.4064)
			(stroke
				(width 0.1524)
				(type default)
			)
			(layer "B.SilkS")
		)
		(fp_line
			(start 0.7874 -0.4064)
			(end -0.7874 -0.4064)
			(stroke
				(width 0.1524)
				(type default)
			)
			(layer "B.SilkS")
		)
		(fp_line
			(start 0.7874 0.4064)
			(end 0.7874 -0.4064)
			(stroke
				(width 0.1524)
				(type default)
			)
			(layer "B.SilkS")
		)
		(fp_poly
			(pts
				(xy 0.508 0.2794) (xy 0.508 0.2286) (xy 0.635 0.2286) (xy 0.635 -0.254) (xy 0.5334 -0.254) (xy 0.5334 -0.2794)
				(xy -0.5334 -0.2794) (xy -0.5334 -0.254) (xy -0.635 -0.254) (xy -0.635 0.254) (xy -0.5334 0.254)
				(xy -0.5334 0.2794)
			)
			(stroke
				(width 0)
				(type default)
			)
			(fill no)
			(layer "B.CrtYd")
		)
		(pad "1" smd rect
			(at -0.40005 0 180)
			(size 0.4572 0.508)
			(layers "B.Cu" "B.Mask" "B.Paste")
			(net "UART_T5_NODE1_RXD")
		)
		(pad "2" smd rect
			(at 0.40005 0 180)
			(size 0.4572 0.508)
			(layers "B.Cu" "B.Mask" "B.Paste")
			(net "UART_T5_NODE1_RXD_R")
		)
	)
	(footprint ""
		(layer "B.Cu")
		(at 154.06116 -175.553624)
		(property "Reference" "R746"
			(at -1.323086 12.476226 0)
			(unlocked yes)
			(layer "B.SilkS")
			(effects
				(font
					(size 0.7874 0.5842)
					(thickness 0.1524)
				)
				(justify left mirror)
			)
		)
		(property "Value" ""
			(at 0 0 0)
			(layer "B.Fab")
			(effects
				(font
					(size 1.27 1.27)
				)
				(justify mirror)
			)
		)
		(duplicate_pad_numbers_are_jumpers no)
		(fp_line
			(start -0.7874 -0.4064)
			(end -0.7874 0.4064)
			(stroke
				(width 0.1524)
				(type default)
			)
			(layer "B.SilkS")
		)
		(fp_line
			(start -0.7874 0.4064)
			(end 0.7874 0.4064)
			(stroke
				(width 0.1524)
				(type default)
			)
			(layer "B.SilkS")
		)
		(fp_line
			(start 0.7874 -0.4064)
			(end -0.7874 -0.4064)
			(stroke
				(width 0.1524)
				(type default)
			)
			(layer "B.SilkS")
		)
		(fp_line
			(start 0.7874 0.4064)
			(end 0.7874 -0.4064)
			(stroke
				(width 0.1524)
				(type default)
			)
			(layer "B.SilkS")
		)
		(fp_poly
			(pts
				(xy 0.508 0.2794) (xy 0.508 0.2286) (xy 0.635 0.2286) (xy 0.635 -0.254) (xy 0.5334 -0.254) (xy 0.5334 -0.2794)
				(xy -0.5334 -0.2794) (xy -0.5334 -0.254) (xy -0.635 -0.254) (xy -0.635 0.254) (xy -0.5334 0.254)
				(xy -0.5334 0.2794)
			)
			(stroke
				(width 0)
				(type default)
			)
			(fill no)
			(layer "B.CrtYd")
		)
		(pad "1" smd rect
			(at -0.40005 0 180)
			(size 0.4572 0.508)
			(layers "B.Cu" "B.Mask" "B.Paste")
			(net "T12_NODE1_EN")
		)
		(pad "2" smd rect
			(at 0.40005 0 180)
			(size 0.4572 0.508)
			(layers "B.Cu" "B.Mask" "B.Paste")
			(net "P5V_NODE1")
		)
	)
)
